# Honey Badger BOM_OCP.xlsx — Pre BOM HB (bom)
| Wiwynn |  |  |  |  |  |  |  | Honey Badger Housing BOM |  |  |  |  |  |
| Model: |  | Honey Badger HU-230H |  |  |  |  |  |  |  |  |  |  |  |
| Project Code.: |  |  |  |  |  |  |  |  |  |  | Version:0.1 |  |  |
| Vendor: |  |  |  |  |  |  |  |  |  |  | 2015/06/12 |  |  |
| No | Level | Part Number |  |  |  | Description | Part Name | Picture | Q'ty | Suppier | Material | Finish | Material  (A,P, M, O SC,CA |
|  |  | 1 | 2 | 3 | 4 |  |  |  |  |  |  |  |  |
|  |  | Main housing |  |  |  |  |  |  |  |  |  |  |  |
|  | 1 | 60.B0731.001 |  |  |  | ASSY MAIN HOUSING NEW C L HB | KNOX_HOUSING_ASSY |  | 1 | Priver |  |  | A |
|  | 2 |  | 60.64W04.001 |  |  | ASSY TOP COVER HU230 | COVER TRAY ASSY |  | 1 | Priver |  |  | M |
|  | 3 |  |  | 34.64W07.001 |  | CVR TOP COVER HU230 | COVER_TRAY_KNOX1 |  | 1 | Priver | SGCC (T=1.0mm) |  | M |
|  | 3 |  |  |  |  | 26-411-201-5 | 43-412-200 |  | 2 | Fivetech | Hardened carbon steel | PENTON 376C | SC |
|  | 3 |  |  |  |  | SO_D4_L4 |  |  | 10 | Priver |  |  | SO |
|  | 3 |  |  |  |  | TOP_COVER_PIN |  |  | 1 | Priver |  |  | SO |
|  | 2 |  | 60.64W05.001 |  |  | ASSY LOWER CASE HU230 | BASE_ASSEMBLY1-1-2011__DEFAULT |  | 1 | Priver |  |  | A |
|  | 3 |  |  | 30.64W01.001 |  | CAS LOWER CASE HU230 | KNOX_LOW_CASE_DEFAULT |  | 1 | Priver | SGCC (T=1.6mm) |  | M |
|  | 4 |  |  |  |  | SO-M3-L12.18MM-GUIDE |  |  | 2 | Priver |  |  | SO |
|  | 4 |  |  |  |  | SO-M3-L10.78MM |  |  | 6 | Priver |  |  | SO |
|  | 4 |  |  |  |  | SO-D3-L6MM |  |  | 1 | Priver |  |  | SO |
|  | 4 |  |  |  |  | FAN_TRAY_GUIDE_PIN |  |  | 8 | Priver |  |  | SO |
|  | 4 |  |  |  |  | BSO-M3-L7.8 |  |  | 4 | Priver |  |  | SO |
|  | 3 |  |  | 33.64W40.001 |  | HLDR TRAY LEFT SLIDE HU230 | HDD_TRAY_SLIDE_1_6MM_right |  | 2 | Priver | SGCC (T=1.6mm) |  | M |
|  | 3 |  |  | 33.64W06.001 |  | HLDR TRAY SLIDE HU230 | HDD_TRAY_SLIDE_1_6MM_left |  | 2 | Priver | SGCC (T=1.6mm) |  | M |
|  | 3 |  |  | 47.64W15.001 |  | RUB HDD TRAY STOPPER HU230 | HDD_TRAY_STOP_RUBBER |  | 4 | PinGood | RUBBER |  | O |
|  | 3 |  |  | 33.64W07.001 |  | BRKT TRAY HOLDER_LEFT | SLIDE_HDD_TRAY_HOLDER_LEFT |  | 2 | Priver | SGCC (T=1.0mm) |  | M |
|  | 3 |  |  | 33.64W08.001 |  | BRKT TRAY HOLDER RIGHT | SLIDE_HDD_TRAY_HOLDER_RIGHT |  | 2 | Priver | SGCC (T=1.0mm) |  | M |
|  | 3 |  |  | 33.64W41.001 |  | BRKT VERTICAL RETAINER HU230 | knox_vertical_retainer_1 |  | 2 | Priver | SUS 301 1/2H (T=0.6mm) |  | M |
|  | 3 |  |  | 33.64W09.001 |  | HLDR FAN TRAY 2 | FAN_TRAY_BRACKET_2_FANS |  | 2 | Priver | SGCC (T=0.8mm) |  | M |
|  | 3 |  |  | 33.64W10.001 |  | HLDR FAN TRAY 1 | FAN_TRAY_BRACKET |  | 2 | Priver | SGCC (T=0.8mm) |  | M |
|  | 3 |  |  | 34.64W08.001 |  | CVR CABLE ARM HOLDER HU230 | CABLE_ARM_HOLDER |  | 1 | Priver | SGCC (T=1.6mm) |  | M |
|  | 3 |  |  | 33.64W11.001 |  | BRKT SENSOR BLOCK HU230 | SENSOR_BLOCK |  | 1 | Priver | SGCC (T=0.8mm) |  | M |
|  | 3 |  |  | 33.64W12.001 |  | HLDR CABLE ARM 1 HU230 | CABLE_ARM_01 |  | 2 | Priver | SGCC (T=1.6mm) |  | M |
|  | 3 |  |  | 33.64W13.001 |  | ASSY LINK ARM HU230 | LINKING_ARM_ASSY_ASM_2 |  | 1 | Priver | SGCC (T=1.6mm) |  | M |
|  | 4 |  |  |  |  | HLDR CABLE ARM 2 HU230 | CABLE_ARM_02 |  | 1 | Priver | SGCC (T=1.6mm) |  | M |
|  | 4 |  |  |  |  | 27-731-501-5 | 54-47-078 |  | 1 | Fivetech | Hardened carbon steel | PENTON 376C | SC |
|  | 3 |  |  | 33.64W13.101 |  | ASSY LINK ARM HU230 | LINKING_ARM_ASSY_ASM_2 |  | 1 | Priver | SGCC (T=1.6mm) |  | M |
|  | 4 |  |  |  |  | HLDR CABLE ARM 2 HU230 | CABLE_ARM_02 |  | 1 | Priver | SGCC (T=1.6mm) |  | M |
|  | 4 |  |  |  |  | 27-731-501-5 | 54-47-078 |  | 1 | Fivetech | Hardened carbon steel | PENTON 376C | SC |
|  | 3 |  |  | 42.64W17.001 |  | STRAP TIE TA14-2C-VO | TA14-2C |  | 11 | PinGood | NYLON |  | O |
|  | 3 |  |  | 42.64W18.001 |  | STRAP TIE BST-6A-VO |  |  | 1 | PinGood | NYLON |  | O |
|  | 3 |  |  | 34.64W09.001 |  | BOSS CABLE ARM 5-82MM HU230 | 5-82MM |  | 1 | Priver | SUS 304(Φ5) |  | O |
|  | 3 |  |  | 34.64W10.001 |  | BOSS CABLE ARM 5-24MM HU230 | 5-24MM |  | 2 | Priver | SUS 304(Φ5) |  | O |
|  | 3 |  |  | 60.64W31.001 |  | ASSY MYLAR TAG BASE HU230 |  |  | 1 | Texchu | Mylar |  | O |
|  | 4 |  |  |  | 40.64W07.001 | MYLAR TAG BASE HU230 | KNOX_SERVICE_TAG_BASE |  | 1 | Texchu | Mylar (T=0.76mm) |  | O |
|  | 4 |  |  |  | 40.64W10.001 | MYLAR TAG BASE HU230 | KNOX_SERVICE_TAG_BASE-1 |  | 1 | Texchu | Mylar (T=0.5mm) |  | O |
|  | 3 |  |  | 40.64W08.001 |  | MYLAR TAG HU230 | KNOX_SERVICE_TAG |  | 1 | Texchu | Mylar (T=0.5mm) |  | O |
|  | 3 |  |  |  |  | ROLLER_WASHER |  |  | 4 | Priver |  |  |  |
|  | 2 |  |  | 33.64W36.001 |  | BRKT SIDE EAR KNOX | KNOX_SIDE_EAR |  | 2 | Priver | SGCC (T=2mm) |  | M |
|  | 2 |  |  | 86.1AS26.8R0 |  | SCRW PAN M4L8 | SIDE EAR SCREW |  | 4 | Wen Haou | SAE1018 |  | SC |
|  | 3 |  |  | 33.64W42.001 |  | HLDR DECELERTOR HU230 | DECELERATOR_SPRING_UPPER_LEFT |  | 2 | Priver | SGCC (T=1.0mm) |  | M |
|  | 3 |  |  | 33.64W43.001 |  | BRKT DECELERATOR SPRING | DECELERATOR_SPRING_LOWER_ANY |  | 4 | Priver | SUS301 1/2H (T=0.6mm) |  | M |
|  | 3 |  |  | 40.64W13.001 |  | MYLAR PLUS HU230 | KNOX_PLUS_MYLAR |  | 1 | Texchu | Red Mylar (T=0.15mm) |  | O |
|  | 3 |  |  | 40.64W14.001 |  | MYLAR MINUS HU230 | KNOX_MINUS_MYLAR |  | 1 | Texchu | Mylar (T=0.15mm) |  | O |
|  | 2 |  | 60.B0730.001 |  |  | ASSY NEW C L HDD TRAY HB | HDD_SUBTRAY_ASSY_WITH_HAR |  | 2 | Priver |  |  | A |
|  | 3 |  |  | 60.64W49.001 |  | ASSY LEFT EJECTOR HU230 |  |  | 1 | Priver |  |  | A |
|  | 4 |  |  |  | 34.64W20.001 | LATCH EJECTOR RELEASE | Ejector_sheet_spring |  | 1 | Priver | SUS301 1/2H (T=0.5mm) |  | M |
|  | 4 |  |  |  | 34.64W18.001 | LATCH EJECTOR LEFT HU230 | ejector_latch_assembly_left_any |  | 1 | Priver | SGCC (T=3.3mm) | Painting PENTON 376C | M |
|  | 5 |  |  |  |  | EJECTOR_PIN |  |  | 1 | Priver |  |  |  |
|  | 4 |  |  |  | 33.64W44.001 | HLDR EJECTOR LEFT HU230 | GEJECTOR_BRACKET_ANY |  | 1 | Priver | SGCC (T=2.5mm) |  | M |
|  | 5 |  |  |  |  | 57-122-149-02 | 57-122-149-02 |  | 1 | Fivetech |  | PENTON 376C | SC |
|  | 5 |  |  |  |  | BSOS-M5-25-Colly |  |  | 1 | Priver |  |  | SO |
|  | 4 |  |  |  | 34.64W21.001 | SPG EJECTOR HU230 | SPRING |  | 1 | HJ spring |  |  | O |
|  | 4 |  |  |  | 86.00T97.26I | SCRW WAFER M4 L2_53 |  |  | 1 | Wen Haou | SAE1018 |  | SC |
|  | 4 |  |  |  | 86.00T98.28C | SCRW WAFER M5 L4_5 |  |  | 1 | Wen Haou | SAE1018 |  | SC |
|  | 4 |  |  |  | 40.64W12.001 | MYLAR EJECTOR HU230 |  |  | 2 | Texchu | Mylar (T=0.15mm) |  | O |
|  | 4 |  |  |  | 47.64W44.001 | SPONGE EJECTOR HU230 |  |  | 1 | Texchu | E4382 (T=3mm) |  | O |
|  | 4 |  |  |  |  | EJECTOR WASHER |  |  | 1 | Priver |  |  | O |
|  | 3 |  |  | 60.64W50.001 |  | ASSY RIGHT EJECTOR HU230 |  |  | 1 | Priver |  |  | A |
|  | 4 |  |  |  | 34.64W20.001 | LATCH EJECTOR RELEASE | Ejector_sheet_spring |  | 1 | Priver |  |  | M |
|  | 4 |  |  |  | 34.64W19.001 | LATCH EJECTOR RIGHT HU230 | ejector_latch_assembly_right_an_asm |  | 1 | Priver | SGCC (T=3.5mm) | Painting PENTON 376C | M |
|  | 5 |  |  |  |  | EJECTOR_PIN |  |  | 1 | Priver |  |  |  |
|  | 4 |  |  |  | 33.64W45.001 | HLDR EJECTOR RIGHT HU230 | EJECTOR_BRACKET_ANY |  | 1 | Priver | SGCC (T=2.5mm) |  | M |
|  | 5 |  |  |  |  | 57-122-149-02 | 57-122-149-02 |  | 1 | Fivetech |  | PENTON 376C | SC |
|  | 5 |  |  |  |  | BSOS-M5-25-Colly |  |  | 1 | Priver |  |  | SO |
|  | 4 |  |  |  | 34.64W22.001 | SPG RIGHT EJECTOR HU230 | SPRING |  | 1 | HJ spring |  |  | O |
|  | 4 |  |  |  | 86.00T97.26I | SCRW WAFER M4 L2_53 |  |  | 1 | Wen Haou | SAE1018 |  | SC |
|  | 4 |  |  |  | 86.00T98.28C | SCRW WAFER M5 L4_5 |  |  | 1 | Wen Haou | SAE1018 |  | SC |
|  | 4 |  |  |  | 40.64W12.001 | MYLAR EJECTOR HU230 |  |  | 2 | Texchu | Mylar (T=0.15mm) |  | O |
|  | 4 |  |  |  | 47.64W44.001 | SPONGE EJECTOR HU230 |  |  | 1 | Texchu | E4382 (T=3mm) |  | O |
|  | 4 |  |  |  |  | EJECTOR WASHER |  |  | 1 | Priver |  |  | O |
|  | 3 |  |  | 33.64W16.101 |  | BRKT HDD TRAY FOR HB | KNOX_HDD_TRAY |  | 1 | Priver (DVT:NCT) (TOOLING MODIFICATION) | SGCC (T=1.2mm) |  | M |
|  | 4 |  |  |  |  | SO-M3-L3.7MM |  |  | 11 | Priver |  |  | SO |
|  | 4 |  |  |  |  | SO-M3-L5.26MM-GUIDE |  |  | 2 | Priver |  |  | SO |
|  | 4 |  |  |  |  | SO-M3-L5.68MM |  |  | 2 | Priver |  |  | SO |
|  | 4 |  |  |  |  | SO-M3-L4.28MM |  |  | 2 | Priver |  |  | SO |
|  | 3 |  |  | 33.64W17.001 |  | BRKT HDD PARTITION HU230 | KNOX_HDD_PARTITION |  | 12 | Priver | SUS 301 1/2H (T=0.5mm) |  | M |
|  | 3 |  |  | 33.64W20.101 |  | BRKT LINK BAR 1 FOR HB | HDD_TRAY_LINK_BAR_1 |  | 1 | Priver (DVT:NCT) (TOOLING MODIFICATION) | SGCC (T=1.6mm) |  | M |
|  |  |  |  |  |  | PIN_LINK_BAR |  |  | 1 | Priver |  |  | SO |
|  | 3 |  |  | 33.64W21.001 |  | BRKT LINK BAR 2 HU230 | HDD_TRAY_LINK_BAR_2_NEW |  | 1 | Priver | SGCC (T=1.2mm) |  | M |
|  | 3 |  |  | 33.64W22.001 |  | BRKT LINK BAR 3 HU230 | HDD_TRAY_LINK_BAR_3_NEW |  | 1 | Priver | SGCC (T=1.2mm) |  | M |
|  | 3 |  |  | 33.64W23.001 |  | BRKT LINK BAR 4 HU230 | HDD_TRAY_LINK_BAR_3 |  | 1 | Priver | SGCC (T=1.2mm) |  | M |
|  | 3 |  |  | 33.B0710.001 |  | BRKT SEB HOLDER HB | seb_holder_asm |  | 1 | Priver | SGCC (T=1.2mm) |  | M |
|  | 3 |  |  | 33.B0704.001 |  | BRKT HDD TRAY HANDLE R HB | seb_holder_asm |  | 1 | Priver | SGCC (T=1.2mm) |  | M |
|  | 3 |  |  | 60.B0721.001 |  | ASSY HDD TRAY HANDLE  L HB |  |  | 1 | Priver |  |  | A |
|  | 4 |  |  | 33.B0712.001 |  | BRKT HDD TRAY HANDLE  L REVIT HB |  |  | 1 | Priver | SGCC (T=1.0mm) |  | M |
|  | 4 |  |  | 33.B0705.001 |  | BRKT HDD TRAY HANDLE  L HB | seb_holder_asm |  | 1 | Priver | SGCC (T=1.0mm) |  | M |
|  | 3 |  |  | 33.64W25.001 |  | BRKT HDD COVER STPOOER HU230 | LINK_BAR_HDD_COVER_STOPPER |  | 15 | Priver | SGCC (T=1.0mm) |  | M |
|  | 3 |  |  | 33.64W28.001 |  | BRKT SEB HOLDER RIGHT HU230 | SEB_HOLDER_BRACKET |  | 1 | Priver | SGCC (T=1.0mm) |  | M |
|  | 3 |  |  | 33.64W29.001 |  | BRKT SEB HOLDER LEFT HU230 | GSEB_HOLDER_BRACKET |  | 1 | Priver | SGCC (T=1.0mm) |  | M |
|  | 3 |  |  | 33.B0711.001 |  | BRKT MIDDLE GUIDE RAIL HB | GSEB_HOLDER_BRACKET |  | 1 | Priver (DVT:NCT) (NEW TOOLING) | SGCC (T=1.0mm) |  | M |
|  | 3 |  |  | 33.64W30.001 |  | BRKT LINK ARM HU230 | HDD_TRAY_LINKING_BAR |  | 1 | Priver | SGCC (T=1.2mm) |  | M |
|  |  |  |  |  |  | SO-M4-L3_65MM |  |  | 1 | Priver |  |  | SO |
|  | 3 |  |  | 86.1AS26.8R0 |  | SCRW PAN M4L8 | SIDE EAR SCREW |  | 1 | Wen Haou | SAE1018 |  | SC |
|  | 3 |  |  | 42.64W06.001 |  | HLDR SEB GUIDE RAIL HU230 | CG-10N |  | 2 | PinGood | NYLON 66 |  | O |
|  | 3 |  |  | 42.B0708.001 |  | HLDR MIDDLE GUIDE RAIL HB | CG-10N |  | 2 | Kang Yang | NYLON 66 |  | O |
|  | 3 |  |  | 47.64W17.001 |  | RUB HDD ISOLATOR HU230 | HDD_ISOLATOR_ |  | 30 | Texchu | E4382 (T=1.6mm) |  | O |
|  | 3 |  |  | 47.64W32.001 |  | RUB HDD STOPPER HU230 |  |  | 30 | Texchu | E4382 (T=1.6mm) |  | O |
|  | 3 |  |  | 47.64W45.001 |  | RUB HDD SIDE ISOLATOR POTENTIAL HU230 |  |  | 15 | Potential |  |  | O |
|  | 3 |  |  | 86.5A534.5R0 |  | SCRW FLAT M3 *5 | SCRW FLAT M3*L4 NI |  | 26 | Wen Haou | SAE1018 |  | SC |
|  | 3 |  |  | 40.64W16.001 |  | MYLAR HDD TRAY DPB MYLAR HU230 |  |  | 1 | Texchu | Mylar (T=0.125mm)  (20130307ADD) |  | O |
|  | 3 |  |  | 40.B0703.001 |  | MYLAR HDD TRAY MYLAR 2 HB | KNOX_HDD_TRAY_MYLAR_2 |  | 1 | Texchu | Mylar (T=0.125mm) |  | O |
|  | 3 |  |  | 40.B0704.001 |  | MYLAR HDD TRAY PTB HB | KNOX_HDD_TRAY_MYLAR_2 |  | 1 | Texchu | Mylar (T=0.125mm) |  | O |
|  | 3 |  |  | 40.64W06.001 |  | MYLAR LINK ARM HU230 | LINKING_ARM_MYLAR |  | 1 | Texchu | Mylar (T=0.2mm) |  | O |
|  | 3 |  |  | 60.64W96.001 |  | ASSY HDD COVER 2 HU230 | KNOX_HDD_COVER_ASM |  | 15 | Priver |  |  | A |
| New | 4 |  |  |  | 34.64W27.001 | CVR HDD COVER 1 HU230 | KNOX_HDD_COVER |  | 1 | Priver | SGCC (T=0.8mm) |  | M |
|  | 4 |  |  |  | 34.64W12.001 | SPG HDD HINGE HU230 | KNOX_HDD_HINGE |  | 1 | HJ spring | SUS 304 (D=2mm) |  | O |
| New | 4 |  |  |  | 34.64W13.101 | LATCH HDD COVER 1 HU230 | KNOX_HDD_LATCH |  | 1 | Priver | SUS 301 1/2H (T=0.5mm) | Painting PENTON 376C | M |
|  | 4 |  |  |  | 47.64W18.001 | RUB HDD PRESS ISOLATOR HU230 | HDD_PRESS_ISOLATOR |  | 1 | Texchu | E4382 (T=6mm) |  | O |
|  | 3 |  |  | 60.64W24.001 |  | ASSY BEARING HOLDER HU230 | BEARING_HOLDER_ASSY |  | 6 | Priver |  |  | A |
|  | 4 |  |  |  | 33.64W31.001 | BRKT BEARING HOLDER HU230 | BEARING_HOLDER |  | 1 | Priver | SGCC (T=1.2mm) |  | M |
|  | 5 |  |  |  |  | BEARING HOLDER STANDOFF |  |  | 1 | Priver |  |  |  |
|  | 4 |  |  |  | 33.64W32.001 | BEARING TRAY HU230 | 7804K105_7804K105 |  | 1 | Priver | SUS304 |  | O |
|  | 4 |  |  |  |  | ROLLER_WASHER |  |  | 1 | Priver |  |  |  |
|  | 3 |  |  | 60.64W27.001 |  | ASSY BEARING HOLDER 3 HU230 | BEARING_HOLDER_FOR_3_BEARING_ASSY |  | 2 | Priver |  |  | A |
|  | 4 |  |  |  | 33.64W33.001 | HLDR BEARING HOLDER HU230 | BEARING_HOLDER_FOR_3_BEARING |  | 1 | Priver | SGCC (T=1.2mm) |  | M |
|  | 5 |  |  |  |  | BEARING HOLDER STANDOFF |  |  | 1 | Priver |  |  |  |
|  | 4 |  |  |  | 33.64W32.001 | BEARING TRAY HU230 | 7804K105_7804K105 |  | 3 | Priver | SUS304 |  | O |
|  | 4 |  |  |  |  | ROLLER_WASHER |  |  | 1 | Priver |  |  |  |
|  | 3 |  |  | 60.64W78.001 |  | ASSY NON-TILTING LEFT HU230 | GHDD_TRAY_HINGE_ASM |  | 1 | Priver |  |  | A |
|  | 4 |  |  |  | 33.64W51.001 | BRKT NON-TILTING LEFT | GASM_HINGE_0319 |  | 1 | Priver |  |  | A |
|  | 4 |  |  |  | 33.64W34.001 | HLDR LEFT HINGE SPRING HU230 | GSPRING_HOLDER_LEFT |  | 1 | Priver | SGCC (T=1.0mm) |  | M |
|  | 4 |  |  |  | 34.64W14.001 | SPG HINGE PUSH SPRING HU230 | HINGE_PUSH_SPRING |  | 1 | HJ spring | SUS 304 (D=1.5mm) |  | O |
|  | 4 |  |  |  | 42.64W07.001 | HLDR HINNGE POM HU230 | HINGE_POM |  | 1 | Shinbo | POM |  | P |
|  | 4 |  |  |  | 34.64W16.001 | LATCH HINGE PUSH LEFT HU230 | GHINGE_BRACKET_LEFT_HOOK |  | 1 | Priver | SGCC (T=1.2mm) | Painting PENTON 376C | M |
|  | 5 |  |  |  |  | HINGE_PUSH_BAR_STANDOFF |  |  | 1 | Priver |  |  |  |
|  | 4 |  |  |  | 34.64W15.001 | SPG PUSH HINGE SPRING 6 HU230 | HINGE_PUSH_SPRING_6 |  | 1 | HJ spring | SUS 304 (D=0.8mm) |  | O |
|  | 4 |  |  |  | 86.00T32.544 | SCRW WAFRE M3.0 L4 NYLOK | 92005A215 |  | 1 | Wen Haou | SAE1018 |  | SC |
|  | 3 |  |  | 60.64W79.001 |  | ASSY NON-TILTING RIGHT HU230 | GHDD_TRAY_HINGE_ASM |  | 1 | Priver |  |  | A |
|  | 4 |  |  |  | 33.64W52.001 | BRKT NON-TILTING RIGHT | GASM_HINGE_0319 |  | 1 | Priver |  |  | A |
|  | 4 |  |  |  | 33.64W35.001 | HLDR RIGHT HINGE SPRING HU230 | GSPRING_HOLDER_LEFT |  | 1 | Priver | SGCC (T=1.0mm) |  | M |
|  | 4 |  |  |  | 34.64W14.001 | SPG HINGE PUSH SPRING HU230 | HINGE_PUSH_SPRING |  | 1 | HJ spring | SUS 304 (D=1.5mm) |  | O |
|  | 4 |  |  |  | 42.64W07.001 | HLDR HINNGE POM HU230 | HINGE_POM |  | 1 | Priver | POM |  | P |
|  | 4 |  |  |  | 34.64W17.001 | LATCH HINGE PUSH RIGHT HU230 | GHINGE_BRACKET_LEFT_HOOK |  | 1 | Priver | SGCC (T=1.2mm) | Painting PENTON 376C | M |
|  |  |  |  |  |  | HINGE_PUSH_BAR_STANDOFF |  |  | 1 | Priver |  |  |  |
|  | 4 |  |  |  | 34.64W15.001 | SPG PUSH HINGE SPRING 6 HU230 | HINGE_PUSH_SPRING_6 |  | 1 | HJ spring | SUS 304 (D=0.8mm) |  | O |
|  | 4 |  |  |  | 86.00T32.544 | SCRW WAFRE M3.0 L4 NYLOK | 92005A215 |  | 1 | Wen Haou | SAE1018 |  | SC |
|  |  | Singal ship |  |  |  |  |  |  |  |  |  |  |  |
|  | 1 | 33.64W48.001 |  |  |  | HLDR HOLDER CHOCK HU230 | KNOX_CHOCK_HOLDER |  | 1 | Priver | SUS301 1/2H (T=0.5mm) |  | M |
|  | 1 | 42.64W16.001 |  |  |  | HLDR PTB GUIDER 1 HU230 | PLASTIC RAMP |  | 2 | Shinbo | PC+ABS |  | P |
|  | 1 | 60.64W43.001 |  |  |  | ASSY SEB RIGHT HANDLE HU230 | KNOX_SEB_HANDLE_ASSY |  | 1 | Priver |  | Painting PENTON 376C | M |
|  | 2 |  | 33.64W01.001 |  |  | BRKT SEB RIGHT HU230 | knox_seb_bracket_any |  | 1 | Priver | SGCC (T=1.0mm) |  | M |
|  | 2 |  |  |  |  | 27-111-201-5 | 46-111-215 |  | 1 | Fivetech | HARDENED CARBON STEEL& ALUMINUM | PENTON 376C | SC |
|  | 1 | 60.64W44.001 |  |  |  | ASSY SEB LEFT HANDLE HU230 | KNOX_SEB_HANDLE_ASSY_LEFT |  | 1 | Priver |  | Painting PENTON 376C | M |
|  | 2 |  | 33.64W05.001 |  |  | BRKT SEB LEFT HU230 | gknox_seb_bracket_any |  | 1 | Priver | SGCC (T=1.0mm) |  | M |
|  | 2 |  |  |  |  | 27-111-201-5 | 46-111-215 |  | 1 | Fivetech | HARDENED CARBON STEEL& ALUMINUM | PENTON 376C | SC |
|  | 1 | 42.64W15.001 |  |  |  | HLDR FAN CONN 1 HU230 | FAN_CONN_HOLDER |  | 6 | Shinbo | PC+ABS |  | P |
|  |  | DELTA fan module(Singal ship) |  |  |  |  |  |  |  |  |  |  |  |
|  | 1 | 60.64W07.001 |  |  |  | ASSY FAN TRAY HU230 | FAN_TRAY_ASSY |  | 6 | Priver |  |  | A |
|  | 2 |  | 60.64W20.001 |  |  | ASSY FAN CAGE HU230 | KNOX_FAN_TRAY |  | 1 | Priver |  |  | M |
|  | 3 |  |  | 33.64W14.001 |  | HLDR FAN TRAY HU230 | FAN_TRAY |  | 1 | Priver | SGCC (T=0.8mm) |  | M |
|  | 3 |  |  |  |  | 27-111-201-5 | 13-111-501 |  | 1 | Fivetech |  | PENTON 376C | SC |
|  | 3 |  |  |  |  | FAN_TRAY_GUIDE_PIN_0.8MM |  |  | 2 | Priver |  |  | SO |
|  | 2 |  | 33.64W37.001 |  |  | BRKT FAN LINKING HU230 | FILLET13 |  | 2 | Priver | SGCC (T=0.8mm) |  | M |
|  | 2 |  | 33.64W15.001 |  |  | HLDR FAN HANDLE HU230 | FAN_TRAY_HANDLE |  | 1 | Priver | SGCC (T=0.8mm) |  | M |
|  |  | Sunon fan module(Singal ship) |  |  |  |  |  |  |  |  |  |  |  |
|  | 1 | 60.64W48.001 |  |  |  | ASSY SUNON FAN CAGE HU230 | FAN_TRAY_ASSY |  | 6 | Priver |  |  | A |
|  | 2 |  | 60.64W42.001 |  |  | ASSY SUNON FAN CAGE | KNOX_FAN_TRAY |  | 1 | Priver |  |  | M |
|  | 3 |  |  | 33.64W47.001 |  | HLDR SUNON FAN TRAY HU230 | FAN_TRAY |  | 1 | Priver | SGCC (T=0.8mm) |  | M |
|  | 3 |  |  |  |  | 27-111-201-5 | 13-111-501 |  | 1 | Fivetech |  | PENTON 376C | SC |
|  | 3 |  |  |  |  | FAN_TRAY_GUIDE_PIN_0.8MM |  |  | 2 | Priver |  |  | SO |
|  | 2 |  | 33.64W37.001 |  |  | BRKT FAN LINKING HU230 | FILLET13 |  | 2 | Priver | SGCC (T=0.8mm) |  | M |
|  | 2 |  | 33.64W15.001 |  |  | HLDR FAN HANDLE HU230 | FAN_TRAY_HANDLE |  | 1 | Priver | SGCC (T=0.8mm) |  | M |
|  |  | Fan module accessory(Singal ship) |  |  |  |  |  |  |  |  |  |  |  |
|  | 1 | 31.64W01.001 |  |  |  | PLT FAN CONN STOPPER HU230 | FAN_TRAY_CONNECTOR_STOP |  | 6 | Priver | SGCC (T=0.8mm) |  | M |
|  | 1 | 42.64W14.001 |  |  |  | HLDR FAN CONN HOLDER 1 HU230 | FAN_TRAY_CONN_HOLDER |  | 6 | Shinbo | PC+ABS |  | P |
|  |  | BASE BOARD(Singal ship) |  |  |  |  |  |  |  |  |  |  |  |
|  | 1 | 60.B0725.001 |  |  |  | ASSY BASE BOARD RIGHT HANDLE HB PVT | KNOX_SEB_HANDLE_ASSY |  | 1 | Priver (DVT:NCT) (NEW TOOLING) | SGCC t1.0 |  | A |
|  | 2 |  | 33.B0702.001 |  |  | BRKT BASE BOARD HANDLE R HB |  |  | 1 | Priver |  |  | O |
|  | 2 |  |  |  |  | 27-111-201-5 | 46-111-215 |  | 1 | Fivetech | HARDENED CARBON STEEL& ALUMINUM |  | SC |
|  | 1 | 60.B0738.001 |  |  |  | ASSY BASE BOARD LEFT HANDLE HB S | KNOX_SEB_HANDLE_ASSY_LEFT |  | 1 | Priver 60.B0726.001 |  |  | A |
|  | 2 |  | 33.B0703.101 |  |  | BRKT BASE BOARD HANDLE L HB S |  |  | 1 | Priver | SGCC t1.0 |  | O |
|  | 2 |  | 33.B0709.001 |  |  | BRKT BASE BOARD PIN L HB |  |  | 1 | Priver | SUS301 t0.8 |  | O |
|  | 1 | 60.B0733.001 |  |  |  | ASSY PANTHER GUIDE RIGHT HB GREEN | KNOX_SEB_HANDLE_ASSY |  | 1 | Priver |  |  | A |
|  | 2 |  | 60.B0734.001 |  |  | ASSY CARD GUIDE R HB GREEN | KNOX_SEB_HANDLE_ASSY |  | 1 | Shinbo |  |  | A |
|  | 3 |  |  | 42.B0711.011 |  | CARD GUIDE R HB  GREEN |  |  | 1 | Shinbo | NFrPP329FR-Green |  | O |
|  | 3 |  |  | 42.B0713.011 |  | LATCH RETAINER HB GREEN |  |  | 1 | Shinbo | NFrPP329FR-Green |  | O |
|  | 3 |  |  | 34.B0703.001 |  | BOSS CARD LATCH PIN HB |  |  | 1 | Wen Haou |  |  | O |
|  | 2 |  | 33.B0701.001 |  |  | BRKT CARD GUIDE HB |  |  | 1 | Priver (DVT:NCT) (NEW TOOLING) | SGCC t1.0 |  | O |
|  | 2 |  | 86.LA534.6R0 |  |  | SCRW TAP FLT 3*T24*6TP-NI |  |  | 2 | Wen Haou |  |  | SC |
|  | 1 | 60.B0732.001 |  |  |  | ASSY PANTHER GUIDE LEFT HB GREEN | KNOX_SEB_HANDLE_ASSY |  | 1 | Priver |  |  | A |
|  | 2 |  | 60.B0735.001 |  |  | ASSY CARD GUIDE L HB GREEN | KNOX_SEB_HANDLE_ASSY |  | 1 | Shinbo |  |  | A |
|  | 3 |  |  | 42.B0712.011 |  | CARD GUIDE L HB GREEN |  |  | 1 | Shinbo | NFrPP329FR-Green |  | O |
|  | 3 |  |  | 42.B0713.011 |  | LATCH RETAINER HB GREEN |  |  | 1 | Shinbo | NFrPP329FR-Green |  | O |
|  | 3 |  |  | 34.B0703.001 |  | BOSS CARD LATCH PIN HB |  |  | 1 | Wen Haou |  |  | O |
|  | 2 |  | 33.B0701.001 |  |  | BRKT CARD GUIDE HB |  |  | 1 | Priver | SGCC t1.0 |  | O |
|  | 2 |  | 86.LA534.6R0 |  |  | SCRW TAP FLT 3*T24*6TP-NI |  |  | 2 | Wen Haou |  |  | SC |
|  | 1 | 33.B0713.001 |  |  |  | BRKT BASE BOARD GUIDE HB PVT | KNOX_SEB_HANDLE_ASSY |  | 1 | Priver | SGCC t1.0 |  | A |
|  |  |  |  |  |  | NUT_M3 |  |  | 1 | Priver |  |  | SO |
|  | 1 | 42.B0717.201 |  |  |  | CVR L PANTHER PLUS HB | 92005A215 |  | 1 | Shinbo | PC 透明/表面拋光 |  | SC |
|  |  | Panther Plus (164) |  |  |  |  |  |  |  |  |  |  |  |
|  | 1 | 42.B0721.001 |  |  |  | HDLR M SATA HB GREEN | 92005A215 |  | 1 | Kang Yang | Pantone 375C | Pantone 375C | SC |
|  | 1 | 086.0002Y.0824 |  |  |  | SCRW WAFRE M2.0 TAP L3.8 | 92005A215 |  | 2 | Wen Haou |  |  | SC |
|  | 1 | 42.B0724.001 |  |  |  | HDLR NGFF HB GREEN | 92005A215 |  | 1 | Kang Yang | Pantone 375C | Pantone 375C | SC |
|  | 1 | 42.B0723.101 |  |  |  | HLDR GRIP PANTHER HB GREEN S | 92005A215 |  | 1 | Shinbo | NFrPP329FR-Green |  | SC |
|  | 1 | 086.0004K.0328 |  |  |  | SCRW WAFRE M2L8 NI | 92005A215 |  | 2 | Wen Haou |  |  | SC |
|  | 1 | 087.0002T.0320 |  |  |  | NUT M2X3.0 PC | 92005A215 |  | 2 | Kang Yang |  |  | SC |
|  |  | Fan |  |  |  |  |  |  |  |  |  |  |  |
|  | 1 | 23.10762.001 |  |  |  | FAN LOW 5P50MM DELTA 60X60X56MM KNOX | 92005A215 |  | 1 | Delta |  |  | FAN |
|  | 2 | 23.10763.001 |  |  |  | FAN LOW 5P50MM SUNON 60X60X60MM KNOX |  |  | 1 | Sunon |  |  | FAN |
|  |  | Cable |  |  |  |  |  |  |  |  |  |  |  |
|  | 1 | 50.64W23.001 |  |  |  | C.A.ALLTOP 2P20S2P L1020 HU230 | 92005A215 |  | 2 | ALL-TOP |  |  | CA |
|  | 1A | 50.64W37.001 |  |  |  | C.A. PWR 2P20S2P L1020 HU230 |  |  | 2 | FCI |  |  | CA |
|  | 2 | 50.64W28.001 |  |  |  | C.A. BUS BAR CLIP 215MM HU230 |  |  | 1 | PORTEN |  |  | CA |
